(kicad_pcb
	(version 20260206)
	(generator "pcbnew")
	(generator_version "10.0")
	(general
		(thickness 1.6)
		(legacy_teardrops no)
	)
	(paper "A4")
	(title_block
		(title "v1-chassis-manager — T6M_CM_d_v01_1031_1645.brd")
		(comment 1 "Open CloudServer (Microsoft) / footprints 1132-1141 of 2512")
	)
	(layers
		(0 "F.Cu" signal "TOP")
		(4 "In1.Cu" signal "GND1")
		(6 "In2.Cu" signal "IN1")
		(8 "In3.Cu" signal "VCC1")
		(10 "In4.Cu" signal "VCC2")
		(12 "In5.Cu" signal "GND2")
		(14 "In6.Cu" signal "IN2")
		(16 "In7.Cu" signal "IN3")
		(18 "In8.Cu" signal "GND3")
		(2 "B.Cu" signal "BOTTOM")
		(9 "F.Adhes" user "F.Adhesive")
		(11 "B.Adhes" user "B.Adhesive")
		(13 "F.Paste" user "Package Geometry/Pastemask Top")
		(15 "B.Paste" user "Package Geometry/Pastemask Bottom")
		(5 "F.SilkS" user "Ref Des/Silkscreen Top")
		(7 "B.SilkS" user "Ref Des/Silkscreen Bottom")
		(1 "F.Mask" user "Board Geometry/Soldermask Top")
		(3 "B.Mask" user "Board Geometry/Soldermask Bottom")
		(17 "Dwgs.User" user "User.Drawings")
		(19 "Cmts.User" user "User.Comments")
		(21 "Eco1.User" user "User.Eco1")
		(23 "Eco2.User" user "User.Eco2")
		(25 "Edge.Cuts" user "Board Geometry/Outline")
		(27 "Margin" user)
		(31 "F.CrtYd" user "Package Geometry/Place Bound Top")
		(29 "B.CrtYd" user "Package Geometry/Place Bound Bottom")
		(35 "F.Fab" user "Ref Des/Assembly Top")
		(33 "B.Fab" user "Ref Des/Assembly Bottom")
	)
	(footprint ""
		(layer "F.Cu")
		(at 139.36218 -75.393296 180)
		(property "Reference" "R507"
			(at -0.948182 2.060448 0)
			(unlocked yes)
			(layer "F.SilkS")
			(effects
				(font
					(size 0.7874 0.5842)
					(thickness 0.1524)
				)
				(justify left)
			)
		)
		(property "Value" ""
			(at 0 0 180)
			(layer "F.Fab")
			(effects
				(font
					(size 1.27 1.27)
				)
			)
		)
		(duplicate_pad_numbers_are_jumpers no)
		(fp_line
			(start 0.7874 0.4064)
			(end -0.7874 0.4064)
			(stroke
				(width 0.1524)
				(type default)
			)
			(layer "F.SilkS")
		)
		(fp_line
			(start 0.7874 -0.4064)
			(end 0.7874 0.4064)
			(stroke
				(width 0.1524)
				(type default)
			)
			(layer "F.SilkS")
		)
		(fp_line
			(start -0.7874 0.4064)
			(end -0.7874 -0.4064)
			(stroke
				(width 0.1524)
				(type default)
			)
			(layer "F.SilkS")
		)
		(fp_line
			(start -0.7874 -0.4064)
			(end 0.7874 -0.4064)
			(stroke
				(width 0.1524)
				(type default)
			)
			(layer "F.SilkS")
		)
		(fp_poly
			(pts
				(xy -0.508 0.2794) (xy -0.508 0.2286) (xy -0.635 0.2286) (xy -0.635 -0.254) (xy -0.5334 -0.254)
				(xy -0.5334 -0.2794) (xy 0.5334 -0.2794) (xy 0.5334 -0.254) (xy 0.635 -0.254) (xy 0.635 0.254) (xy 0.5334 0.254)
				(xy 0.5334 0.2794)
			)
			(stroke
				(width 0)
				(type default)
			)
			(fill no)
			(layer "F.CrtYd")
		)
		(pad "1" smd rect
			(at 0.40005 0 180)
			(size 0.4572 0.508)
			(layers "F.Cu" "F.Mask" "F.Paste")
			(net "SATA_SPI_CS_NODE1")
		)
		(pad "2" smd rect
			(at -0.40005 0 180)
			(size 0.4572 0.508)
			(layers "F.Cu" "F.Mask" "F.Paste")
			(net "SATA_SPI_CS_NODE1_R")
		)
	)
	(footprint ""
		(layer "F.Cu")
		(at 143.528796 -181.506622 -90)
		(property "Reference" "R807"
			(at 1.560322 -2.09169 90)
			(unlocked yes)
			(layer "F.SilkS")
			(effects
				(font
					(size 0.7874 0.5842)
					(thickness 0.1524)
				)
				(justify left)
			)
		)
		(property "Value" ""
			(at 0 0 270)
			(layer "F.Fab")
			(effects
				(font
					(size 1.27 1.27)
				)
			)
		)
		(duplicate_pad_numbers_are_jumpers no)
		(fp_line
			(start -0.7874 0.4064)
			(end -0.7874 -0.4064)
			(stroke
				(width 0.1524)
				(type default)
			)
			(layer "F.SilkS")
		)
		(fp_line
			(start 0.7874 0.4064)
			(end -0.7874 0.4064)
			(stroke
				(width 0.1524)
				(type default)
			)
			(layer "F.SilkS")
		)
		(fp_line
			(start -0.7874 -0.4064)
			(end 0.7874 -0.4064)
			(stroke
				(width 0.1524)
				(type default)
			)
			(layer "F.SilkS")
		)
		(fp_line
			(start 0.7874 -0.4064)
			(end 0.7874 0.4064)
			(stroke
				(width 0.1524)
				(type default)
			)
			(layer "F.SilkS")
		)
		(fp_poly
			(pts
				(xy -0.508 0.2794) (xy -0.508 0.2286) (xy -0.635 0.2286) (xy -0.635 -0.254) (xy -0.5334 -0.254)
				(xy -0.5334 -0.2794) (xy 0.5334 -0.2794) (xy 0.5334 -0.254) (xy 0.635 -0.254) (xy 0.635 0.254) (xy 0.5334 0.254)
				(xy 0.5334 0.2794)
			)
			(stroke
				(width 0)
				(type default)
			)
			(fill no)
			(layer "F.CrtYd")
		)
		(pad "1" smd rect
			(at 0.40005 0 270)
			(size 0.4572 0.508)
			(layers "F.Cu" "F.Mask" "F.Paste")
			(net "CPLD_UART_DTR_P3_N")
		)
		(pad "2" smd rect
			(at -0.40005 0 270)
			(size 0.4572 0.508)
			(layers "F.Cu" "F.Mask" "F.Paste")
			(net "GND")
		)
	)
	(footprint ""
		(layer "F.Cu")
		(at 29.561282 -147.961858 90)
		(property "Reference" "R565"
			(at -1.005332 1.764538 90)
			(unlocked yes)
			(layer "F.SilkS")
			(effects
				(font
					(size 0.7874 0.5842)
					(thickness 0.1524)
				)
				(justify left)
			)
		)
		(property "Value" ""
			(at 0 0 90)
			(layer "F.Fab")
			(effects
				(font
					(size 1.27 1.27)
				)
			)
		)
		(duplicate_pad_numbers_are_jumpers no)
		(fp_line
			(start 2.2098 -0.9398)
			(end 2.2098 0.9398)
			(stroke
				(width 0.1524)
				(type default)
			)
			(layer "F.SilkS")
		)
		(fp_line
			(start -2.2098 -0.9398)
			(end 2.2098 -0.9398)
			(stroke
				(width 0.1524)
				(type default)
			)
			(layer "F.SilkS")
		)
		(fp_line
			(start 2.2098 0.9398)
			(end -2.2098 0.9398)
			(stroke
				(width 0.1524)
				(type default)
			)
			(layer "F.SilkS")
		)
		(fp_line
			(start -2.2098 0.9398)
			(end -2.2098 -0.9398)
			(stroke
				(width 0.1524)
				(type default)
			)
			(layer "F.SilkS")
		)
		(fp_poly
			(pts
				(xy 2.0574 0.8382) (xy 2.0574 -0.8382) (xy 2.0574 -0.9398) (xy -2.0574 -0.9398) (xy -2.0574 -0.8382)
				(xy -2.0574 0.8382) (xy -2.0574 0.9398) (xy 2.0574 0.9398)
			)
			(stroke
				(width 0)
				(type default)
			)
			(fill no)
			(layer "F.CrtYd")
		)
		(pad "1" smd rect
			(at 1.4732 0 90)
			(size 1.1684 1.5748)
			(layers "F.Cu" "F.Mask" "F.Paste")
			(net "LAN1_CTRL_P1V9")
		)
		(pad "2" smd rect
			(at -1.4732 0 90)
			(size 1.1684 1.5748)
			(layers "F.Cu" "F.Mask" "F.Paste")
			(net "LAN1_CTRL_P1V9_R")
		)
	)
	(footprint ""
		(layer "F.Cu")
		(at 104.073452 -162.781488)
		(property "Reference" "R1003"
			(at 87.099648 71.74738 0)
			(unlocked yes)
			(layer "F.SilkS")
			(effects
				(font
					(size 0.7874 0.5842)
					(thickness 0.1524)
				)
				(justify left)
			)
		)
		(property "Value" ""
			(at 0 0 0)
			(layer "F.Fab")
			(effects
				(font
					(size 1.27 1.27)
				)
			)
		)
		(duplicate_pad_numbers_are_jumpers no)
		(fp_line
			(start -0.7874 -0.4064)
			(end 0.7874 -0.4064)
			(stroke
				(width 0.1524)
				(type default)
			)
			(layer "F.SilkS")
		)
		(fp_line
			(start -0.7874 0.4064)
			(end -0.7874 -0.4064)
			(stroke
				(width 0.1524)
				(type default)
			)
			(layer "F.SilkS")
		)
		(fp_line
			(start 0.7874 -0.4064)
			(end 0.7874 0.4064)
			(stroke
				(width 0.1524)
				(type default)
			)
			(layer "F.SilkS")
		)
		(fp_line
			(start 0.7874 0.4064)
			(end -0.7874 0.4064)
			(stroke
				(width 0.1524)
				(type default)
			)
			(layer "F.SilkS")
		)
		(fp_poly
			(pts
				(xy -0.508 0.2794) (xy -0.508 0.2286) (xy -0.635 0.2286) (xy -0.635 -0.254) (xy -0.5334 -0.254)
				(xy -0.5334 -0.2794) (xy 0.5334 -0.2794) (xy 0.5334 -0.254) (xy 0.635 -0.254) (xy 0.635 0.254) (xy 0.5334 0.254)
				(xy 0.5334 0.2794)
			)
			(stroke
				(width 0)
				(type default)
			)
			(fill no)
			(layer "F.CrtYd")
		)
		(pad "1" smd rect
			(at 0.40005 0)
			(size 0.4572 0.508)
			(layers "F.Cu" "F.Mask" "F.Paste")
			(net "GND")
		)
		(pad "2" smd rect
			(at -0.40005 0)
			(size 0.4572 0.508)
			(layers "F.Cu" "F.Mask" "F.Paste")
			(net "POWER_SW1_PWR_CTR_12V")
		)
	)
	(footprint ""
		(layer "F.Cu")
		(at 193.170556 -144.898872 180)
		(property "Reference" "C475"
			(at -3.82651 0.233172 0)
			(unlocked yes)
			(layer "F.SilkS")
			(effects
				(font
					(size 0.7874 0.5842)
					(thickness 0.1524)
				)
			)
		)
		(property "Value" ""
			(at 0 0 180)
			(layer "F.Fab")
			(effects
				(font
					(size 1.27 1.27)
				)
			)
		)
		(duplicate_pad_numbers_are_jumpers no)
		(fp_line
			(start 1.2954 0.5842)
			(end -1.2954 0.5842)
			(stroke
				(width 0.1524)
				(type default)
			)
			(layer "F.SilkS")
		)
		(fp_line
			(start 1.2954 -0.5842)
			(end 1.2954 0.5842)
			(stroke
				(width 0.1524)
				(type default)
			)
			(layer "F.SilkS")
		)
		(fp_line
			(start 0 -0.5842)
			(end 0 0.5842)
			(stroke
				(width 0.1524)
				(type default)
			)
			(layer "F.SilkS")
		)
		(fp_line
			(start -1.2954 0.5842)
			(end -1.2954 -0.5842)
			(stroke
				(width 0.1524)
				(type default)
			)
			(layer "F.SilkS")
		)
		(fp_line
			(start -1.2954 -0.5842)
			(end 1.2954 -0.5842)
			(stroke
				(width 0.1524)
				(type default)
			)
			(layer "F.SilkS")
		)
		(fp_poly
			(pts
				(xy 0.8636 -0.4572) (xy 0.8636 -0.3556) (xy 1.143 -0.3556) (xy 1.143 0.3556) (xy 0.8636 0.3556)
				(xy 0.8636 0.4572) (xy -0.8636 0.4572) (xy -0.8636 0.3556) (xy -1.143 0.3556) (xy -1.143 -0.3556)
				(xy -0.8636 -0.3556) (xy -0.8636 -0.4572)
			)
			(stroke
				(width 0)
				(type default)
			)
			(fill no)
			(layer "F.CrtYd")
		)
		(fp_line
			(start 0.884936 0.504952)
			(end -0.884936 0.504952)
			(stroke
				(width 0.1)
				(type default)
			)
			(layer "F.Fab")
		)
		(fp_line
			(start 0.884936 -0.504952)
			(end 0.884936 0.504952)
			(stroke
				(width 0.1)
				(type default)
			)
			(layer "F.Fab")
		)
		(fp_line
			(start -0.884936 0.504952)
			(end -0.884936 -0.504952)
			(stroke
				(width 0.1)
				(type default)
			)
			(layer "F.Fab")
		)
		(fp_line
			(start -0.884936 -0.504952)
			(end 0.884936 -0.504952)
			(stroke
				(width 0.1)
				(type default)
			)
			(layer "F.Fab")
		)
		(pad "1" smd rect
			(at 0.7366 0 270)
			(size 0.7112 0.8128)
			(layers "F.Cu" "F.Mask" "F.Paste")
			(net "P1V9_LAN2")
		)
		(pad "2" smd rect
			(at -0.7366 0 270)
			(size 0.7112 0.8128)
			(layers "F.Cu" "F.Mask" "F.Paste")
			(net "GND")
		)
	)
	(footprint ""
		(layer "F.Cu")
		(at 94.471236 -166.155878)
		(property "Reference" "C584"
			(at 86.63305 73.147936 0)
			(unlocked yes)
			(layer "F.SilkS")
			(effects
				(font
					(size 0.7874 0.5842)
					(thickness 0.1524)
				)
				(justify left)
			)
		)
		(property "Value" ""
			(at 0 0 0)
			(layer "F.Fab")
			(effects
				(font
					(size 1.27 1.27)
				)
			)
		)
		(duplicate_pad_numbers_are_jumpers no)
		(fp_line
			(start -0.7874 -0.4064)
			(end 0.7874 -0.4064)
			(stroke
				(width 0.1524)
				(type default)
			)
			(layer "F.SilkS")
		)
		(fp_line
			(start -0.7874 0.4064)
			(end -0.7874 -0.4064)
			(stroke
				(width 0.1524)
				(type default)
			)
			(layer "F.SilkS")
		)
		(fp_line
			(start 0 0.381)
			(end 0 -0.381)
			(stroke
				(width 0.1524)
				(type default)
			)
			(layer "F.SilkS")
		)
		(fp_line
			(start 0.7874 -0.4064)
			(end 0.7874 0.4064)
			(stroke
				(width 0.1524)
				(type default)
			)
			(layer "F.SilkS")
		)
		(fp_line
			(start 0.7874 0.4064)
			(end -0.7874 0.4064)
			(stroke
				(width 0.1524)
				(type default)
			)
			(layer "F.SilkS")
		)
		(fp_poly
			(pts
				(xy -0.5334 0.254) (xy -0.635 0.254) (xy -0.635 0.2286) (xy -0.635 -0.254) (xy -0.5334 -0.254) (xy -0.5334 -0.2794)
				(xy 0.5334 -0.2794) (xy 0.5334 -0.254) (xy 0.635 -0.254) (xy 0.635 0.254) (xy 0.5334 0.254) (xy 0.5334 0.2794)
				(xy -0.508 0.2794) (xy -0.5334 0.2794)
			)
			(stroke
				(width 0)
				(type default)
			)
			(fill no)
			(layer "F.CrtYd")
		)
		(pad "1" smd rect
			(at 0.40005 0)
			(size 0.4572 0.508)
			(layers "F.Cu" "F.Mask" "F.Paste")
			(net "P3V3_NODE1")
		)
		(pad "2" smd rect
			(at -0.40005 0)
			(size 0.4572 0.508)
			(layers "F.Cu" "F.Mask" "F.Paste")
			(net "GND")
		)
	)
	(footprint ""
		(layer "F.Cu")
		(at 18.746724 -142.448534)
		(property "Reference" "C414"
			(at -5.348224 -0.447294 0)
			(unlocked yes)
			(layer "F.SilkS")
			(effects
				(font
					(size 0.7874 0.5842)
					(thickness 0.1524)
				)
				(justify left)
			)
		)
		(property "Value" ""
			(at 0 0 0)
			(layer "F.Fab")
			(effects
				(font
					(size 1.27 1.27)
				)
			)
		)
		(duplicate_pad_numbers_are_jumpers no)
		(fp_line
			(start -1.905 -0.8636)
			(end 1.905 -0.8636)
			(stroke
				(width 0.1524)
				(type default)
			)
			(layer "F.SilkS")
		)
		(fp_line
			(start -1.905 0.8636)
			(end -1.905 -0.8636)
			(stroke
				(width 0.1524)
				(type default)
			)
			(layer "F.SilkS")
		)
		(fp_line
			(start 0 0.8382)
			(end 0 -0.8382)
			(stroke
				(width 0.1524)
				(type default)
			)
			(layer "F.SilkS")
		)
		(fp_line
			(start 1.905 -0.8636)
			(end 1.905 0.8636)
			(stroke
				(width 0.1524)
				(type default)
			)
			(layer "F.SilkS")
		)
		(fp_line
			(start 1.905 0.8636)
			(end -1.905 0.8636)
			(stroke
				(width 0.1524)
				(type default)
			)
			(layer "F.SilkS")
		)
		(fp_rect
			(start -1.524 0.7366)
			(end 1.524 -0.7366)
			(stroke
				(width 0)
				(type default)
			)
			(fill no)
			(layer "F.CrtYd")
		)
		(pad "1" smd rect
			(at 0.94996 0)
			(size 1.1176 1.3716)
			(layers "F.Cu" "F.Mask" "F.Paste")
			(net "P3V3_NODE1")
		)
		(pad "2" smd rect
			(at -0.94996 0)
			(size 1.1176 1.3716)
			(layers "F.Cu" "F.Mask" "F.Paste")
			(net "GND")
		)
	)
	(footprint ""
		(layer "F.Cu")
		(at 84.416392 -78.569058 90)
		(property "Reference" "R1049"
			(at -4.007358 1.394714 90)
			(unlocked yes)
			(layer "F.SilkS")
			(effects
				(font
					(size 0.7874 0.5842)
					(thickness 0.1524)
				)
				(justify left)
			)
		)
		(property "Value" ""
			(at 0 0 90)
			(layer "F.Fab")
			(effects
				(font
					(size 1.27 1.27)
				)
			)
		)
		(duplicate_pad_numbers_are_jumpers no)
		(fp_line
			(start 0.7874 -0.4064)
			(end 0.7874 0.4064)
			(stroke
				(width 0.1524)
				(type default)
			)
			(layer "F.SilkS")
		)
		(fp_line
			(start -0.7874 -0.4064)
			(end 0.7874 -0.4064)
			(stroke
				(width 0.1524)
				(type default)
			)
			(layer "F.SilkS")
		)
		(fp_line
			(start 0.7874 0.4064)
			(end -0.7874 0.4064)
			(stroke
				(width 0.1524)
				(type default)
			)
			(layer "F.SilkS")
		)
		(fp_line
			(start -0.7874 0.4064)
			(end -0.7874 -0.4064)
			(stroke
				(width 0.1524)
				(type default)
			)
			(layer "F.SilkS")
		)
		(fp_poly
			(pts
				(xy -0.508 0.2794) (xy -0.508 0.2286) (xy -0.635 0.2286) (xy -0.635 -0.254) (xy -0.5334 -0.254)
				(xy -0.5334 -0.2794) (xy 0.5334 -0.2794) (xy 0.5334 -0.254) (xy 0.635 -0.254) (xy 0.635 0.254) (xy 0.5334 0.254)
				(xy 0.5334 0.2794)
			)
			(stroke
				(width 0)
				(type default)
			)
			(fill no)
			(layer "F.CrtYd")
		)
		(pad "1" smd rect
			(at 0.40005 0 90)
			(size 0.4572 0.508)
			(layers "F.Cu" "F.Mask" "F.Paste")
			(net "FM_CPU_NODE1_JTAG_POK")
		)
		(pad "2" smd rect
			(at -0.40005 0 90)
			(size 0.4572 0.508)
			(layers "F.Cu" "F.Mask" "F.Paste")
			(net "P1V05_NODE1")
		)
	)
	(footprint ""
		(layer "F.Cu")
		(at 32.014668 -171.671234)
		(property "Reference" "C794"
			(at -3.56616 7.439406 0)
			(unlocked yes)
			(layer "F.SilkS")
			(effects
				(font
					(size 0.7874 0.5842)
					(thickness 0.1524)
				)
				(justify left)
			)
		)
		(property "Value" ""
			(at 0 0 0)
			(layer "F.Fab")
			(effects
				(font
					(size 1.27 1.27)
				)
			)
		)
		(duplicate_pad_numbers_are_jumpers no)
		(fp_line
			(start -0.7874 -0.4064)
			(end 0.7874 -0.4064)
			(stroke
				(width 0.1524)
				(type default)
			)
			(layer "F.SilkS")
		)
		(fp_line
			(start -0.7874 0.4064)
			(end -0.7874 -0.4064)
			(stroke
				(width 0.1524)
				(type default)
			)
			(layer "F.SilkS")
		)
		(fp_line
			(start 0 0.381)
			(end 0 -0.381)
			(stroke
				(width 0.1524)
				(type default)
			)
			(layer "F.SilkS")
		)
		(fp_line
			(start 0.7874 -0.4064)
			(end 0.7874 0.4064)
			(stroke
				(width 0.1524)
				(type default)
			)
			(layer "F.SilkS")
		)
		(fp_line
			(start 0.7874 0.4064)
			(end -0.7874 0.4064)
			(stroke
				(width 0.1524)
				(type default)
			)
			(layer "F.SilkS")
		)
		(fp_poly
			(pts
				(xy -0.5334 0.254) (xy -0.635 0.254) (xy -0.635 0.2286) (xy -0.635 -0.254) (xy -0.5334 -0.254) (xy -0.5334 -0.2794)
				(xy 0.5334 -0.2794) (xy 0.5334 -0.254) (xy 0.635 -0.254) (xy 0.635 0.254) (xy 0.5334 0.254) (xy 0.5334 0.2794)
				(xy -0.508 0.2794) (xy -0.5334 0.2794)
			)
			(stroke
				(width 0)
				(type default)
			)
			(fill no)
			(layer "F.CrtYd")
		)
		(pad "1" smd rect
			(at 0.40005 0)
			(size 0.4572 0.508)
			(layers "F.Cu" "F.Mask" "F.Paste")
			(net "CM_PWR_CTL_IN_R")
		)
		(pad "2" smd rect
			(at -0.40005 0)
			(size 0.4572 0.508)
			(layers "F.Cu" "F.Mask" "F.Paste")
			(net "GND")
		)
	)
	(footprint ""
		(layer "F.Cu")
		(at 136.450324 -158.553658)
		(property "Reference" "R647"
			(at -64.67602 108.381038 0)
			(unlocked yes)
			(layer "F.SilkS")
			(effects
				(font
					(size 0.7874 0.5842)
					(thickness 0.1524)
				)
				(justify left)
			)
		)
		(property "Value" ""
			(at 0 0 0)
			(layer "F.Fab")
			(effects
				(font
					(size 1.27 1.27)
				)
			)
		)
		(duplicate_pad_numbers_are_jumpers no)
		(fp_line
			(start -0.7874 -0.4064)
			(end 0.7874 -0.4064)
			(stroke
				(width 0.1524)
				(type default)
			)
			(layer "F.SilkS")
		)
		(fp_line
			(start -0.7874 0.4064)
			(end -0.7874 -0.4064)
			(stroke
				(width 0.1524)
				(type default)
			)
			(layer "F.SilkS")
		)
		(fp_line
			(start 0.7874 -0.4064)
			(end 0.7874 0.4064)
			(stroke
				(width 0.1524)
				(type default)
			)
			(layer "F.SilkS")
		)
		(fp_line
			(start 0.7874 0.4064)
			(end -0.7874 0.4064)
			(stroke
				(width 0.1524)
				(type default)
			)
			(layer "F.SilkS")
		)
		(fp_poly
			(pts
				(xy -0.508 0.2794) (xy -0.508 0.2286) (xy -0.635 0.2286) (xy -0.635 -0.254) (xy -0.5334 -0.254)
				(xy -0.5334 -0.2794) (xy 0.5334 -0.2794) (xy 0.5334 -0.254) (xy 0.635 -0.254) (xy 0.635 0.254) (xy 0.5334 0.254)
				(xy 0.5334 0.2794)
			)
			(stroke
				(width 0)
				(type default)
			)
			(fill no)
			(layer "F.CrtYd")
		)
		(pad "1" smd rect
			(at 0.40005 0)
			(size 0.4572 0.508)
			(layers "F.Cu" "F.Mask" "F.Paste")
			(net "I2C_PSU3_SDA")
		)
		(pad "2" smd rect
			(at -0.40005 0)
			(size 0.4572 0.508)
			(layers "F.Cu" "F.Mask" "F.Paste")
			(net "I2C_PSU3_SDA_MOS")
		)
	)
)
